(kicad_pcb
	(version 20260206)
	(generator "pcbnew")
	(generator_version "10.0")
	(general
		(thickness 1.6)
		(legacy_teardrops no)
	)
	(paper "A4")
	(title_block
		(title "01162023_DA0F0TEBIF0_F0T_Expander_BD_F_brd_V02_OCP.brd")
		(comment 1 "Grand Teton / footprint 3896 of 9728 (J12), pads 1-77 of 142")
	)
	(layers
		(0 "F.Cu" signal "TOP")
		(4 "In1.Cu" signal "GND")
		(6 "In2.Cu" signal "VCC")
		(8 "In3.Cu" signal "VCC1")
		(10 "In4.Cu" signal "GND1")
		(12 "In5.Cu" signal "IN1")
		(14 "In6.Cu" signal "GND2")
		(16 "In7.Cu" signal "IN2")
		(18 "In8.Cu" signal "GND3")
		(20 "In9.Cu" signal "IN3")
		(22 "In10.Cu" signal "GND4")
		(24 "In11.Cu" signal "IN4")
		(26 "In12.Cu" signal "GND5")
		(28 "In13.Cu" signal "IN5")
		(30 "In14.Cu" signal "GND6")
		(32 "In15.Cu" signal "IN6")
		(34 "In16.Cu" signal "GND7")
		(2 "B.Cu" signal "BOTTOM")
		(9 "F.Adhes" user "F.Adhesive")
		(11 "B.Adhes" user "B.Adhesive")
		(13 "F.Paste" user "Package Geometry/Pastemask Top")
		(15 "B.Paste" user "Package Geometry/Pastemask Bottom")
		(5 "F.SilkS" user "Ref Des/Silkscreen Top")
		(7 "B.SilkS" user "Ref Des/Silkscreen Bottom")
		(1 "F.Mask" user "Board Geometry/Soldermask Top")
		(3 "B.Mask" user "Board Geometry/Soldermask Bottom")
		(17 "Dwgs.User" user "User.Drawings")
		(19 "Cmts.User" user "User.Comments")
		(21 "Eco1.User" user "User.Eco1")
		(23 "Eco2.User" user "User.Eco2")
		(25 "Edge.Cuts" user "Board Geometry/Outline")
		(27 "Margin" user)
		(31 "F.CrtYd" user "Package Geometry/Place Bound Top")
		(29 "B.CrtYd" user "Package Geometry/Place Bound Bottom")
		(35 "F.Fab" user "Ref Des/Assembly Top")
		(33 "B.Fab" user "Ref Des/Assembly Bottom")
	)
	(footprint ""
		(layer "F.Cu")
		(at 115.910106 -412.090108)
		(property "Reference" "J12"
			(at 26.161492 4.719066 90)
			(unlocked yes)
			(layer "F.SilkS")
			(effects
				(font
					(size 2.032 1.524)
					(thickness 0.1524)
				)
				(justify left)
			)
		)
		(property "Value" ""
			(at 0 0 0)
			(layer "F.Fab")
			(effects
				(font
					(size 1.27 1.27)
				)
			)
		)
		(duplicate_pad_numbers_are_jumpers no)
		(pad "A1" thru_hole rect
			(at 0 0 180)
			(size 0.71628 0.71628)
			(drill 0.30988)
			(layers "*.Cu" "*.Mask")
			(remove_unused_layers no)
			(net "GPU_FPGA_EROT_RECOV_N")
			(clearance 0.0508)
			(thermal_gap 0.0508)
			(padstack
				(mode front_inner_back)
				(layer "Inner"
					(shape circle)
					(size 0.71628 0.71628)
					(clearance 0.0508)
				)
				(layer "B.Cu"
					(shape rect)
					(size 0.71628 0.71628)
					(clearance 0.0508)
				)
			)
		)
		(pad "A2" thru_hole circle
			(at 2.199894 0.199898 180)
			(size 0.906272 0.906272)
			(drill 0.499872)
			(layers "*.Cu" "*.Mask")
			(remove_unused_layers no)
			(net "GND")
			(clearance 0.0508)
			(thermal_gap 0.0508)
		)
		(pad "A3" thru_hole circle
			(at 4.400042 0 180)
			(size 0.71628 0.71628)
			(drill 0.30988)
			(layers "*.Cu" "*.Mask")
			(remove_unused_layers no)
			(net "PRSNT_GPU_HMC_R_N")
			(clearance 0.0508)
			(thermal_gap 0.0508)
		)
		(pad "A4" thru_hole circle
			(at 6.599936 0.199898 180)
			(size 0.906272 0.906272)
			(drill 0.499872)
			(layers "*.Cu" "*.Mask")
			(remove_unused_layers no)
			(net "GND")
			(clearance 0.0508)
			(thermal_gap 0.0508)
		)
		(pad "A5" thru_hole circle
			(at 8.800084 0 180)
			(size 0.71628 0.71628)
			(drill 0.30988)
			(layers "*.Cu" "*.Mask")
			(remove_unused_layers no)
			(net "GPU_BASE_HMC_READY_R")
			(clearance 0.0508)
			(thermal_gap 0.0508)
		)
		(pad "A6" thru_hole circle
			(at 10.999978 0.199898 180)
			(size 0.906272 0.906272)
			(drill 0.499872)
			(layers "*.Cu" "*.Mask")
			(remove_unused_layers no)
			(net "GND")
			(clearance 0.0508)
			(thermal_gap 0.0508)
		)
		(pad "A7" thru_hole circle
			(at 13.199872 0 180)
			(size 0.71628 0.71628)
			(drill 0.30988)
			(layers "*.Cu" "*.Mask")
			(remove_unused_layers no)
			(net "GPU_BASE_STBY_EN")
			(clearance 0.0508)
			(thermal_gap 0.0508)
		)
		(pad "A8" thru_hole circle
			(at 15.40002 0.199898 180)
			(size 0.906272 0.906272)
			(drill 0.499872)
			(layers "*.Cu" "*.Mask")
			(remove_unused_layers no)
			(net "GND")
			(clearance 0.0508)
			(thermal_gap 0.0508)
		)
		(pad "A9" thru_hole circle
			(at 17.599914 0 180)
			(size 0.71628 0.71628)
			(drill 0.30988)
			(layers "*.Cu" "*.Mask")
			(remove_unused_layers no)
			(net "SMB_MB_BMC_SDA")
			(clearance 0.0508)
			(thermal_gap 0.0508)
		)
		(pad "A10" thru_hole circle
			(at 19.800062 0.199898 180)
			(size 0.906272 0.906272)
			(drill 0.499872)
			(layers "*.Cu" "*.Mask")
			(remove_unused_layers no)
			(net "GND")
			(clearance 0.0508)
			(thermal_gap 0.0508)
		)
		(pad "B1" thru_hole circle
			(at 0 1.299972 180)
			(size 0.906272 0.906272)
			(drill 0.499872)
			(layers "*.Cu" "*.Mask")
			(remove_unused_layers no)
			(net "GND")
			(clearance 0.0508)
			(thermal_gap 0.0508)
		)
		(pad "B3" thru_hole circle
			(at 4.400042 1.299972 180)
			(size 0.906272 0.906272)
			(drill 0.499872)
			(layers "*.Cu" "*.Mask")
			(remove_unused_layers no)
			(net "GND")
			(clearance 0.0508)
			(thermal_gap 0.0508)
		)
		(pad "B5" thru_hole circle
			(at 8.800084 1.299972 180)
			(size 0.906272 0.906272)
			(drill 0.499872)
			(layers "*.Cu" "*.Mask")
			(remove_unused_layers no)
			(net "GND")
			(clearance 0.0508)
			(thermal_gap 0.0508)
		)
		(pad "B7" thru_hole circle
			(at 13.199872 1.299972 180)
			(size 0.906272 0.906272)
			(drill 0.499872)
			(layers "*.Cu" "*.Mask")
			(remove_unused_layers no)
			(net "GND")
			(clearance 0.0508)
			(thermal_gap 0.0508)
		)
		(pad "B9" thru_hole circle
			(at 17.599914 1.299972 180)
			(size 0.906272 0.906272)
			(drill 0.499872)
			(layers "*.Cu" "*.Mask")
			(remove_unused_layers no)
			(net "GND")
			(clearance 0.0508)
			(thermal_gap 0.0508)
		)
		(pad "B10" thru_hole circle
			(at 19.800062 1.500124 180)
			(size 0.71628 0.71628)
			(drill 0.30988)
			(layers "*.Cu" "*.Mask")
			(remove_unused_layers no)
			(net "Net_4583")
			(clearance 0.0508)
			(thermal_gap 0.0508)
		)
		(pad "C9" thru_hole circle
			(at 17.599914 2.599944 180)
			(size 0.71628 0.71628)
			(drill 0.30988)
			(layers "*.Cu" "*.Mask")
			(remove_unused_layers no)
			(net "SMB_GPU2_ALERT_R_N")
			(clearance 0.0508)
			(thermal_gap 0.0508)
		)
		(pad "C10" thru_hole circle
			(at 19.800062 2.800096 180)
			(size 0.71628 0.71628)
			(drill 0.30988)
			(layers "*.Cu" "*.Mask")
			(remove_unused_layers no)
			(net "Net_4584")
			(clearance 0.0508)
			(thermal_gap 0.0508)
		)
		(pad "D2" thru_hole circle
			(at 2.199894 4.100068 180)
			(size 0.906272 0.906272)
			(drill 0.499872)
			(layers "*.Cu" "*.Mask")
			(remove_unused_layers no)
			(net "GND")
			(clearance 0.0508)
			(thermal_gap 0.0508)
		)
		(pad "D4" thru_hole circle
			(at 6.599936 4.100068 180)
			(size 0.906272 0.906272)
			(drill 0.499872)
			(layers "*.Cu" "*.Mask")
			(remove_unused_layers no)
			(net "GND")
			(clearance 0.0508)
			(thermal_gap 0.0508)
		)
		(pad "D6" thru_hole circle
			(at 10.999978 4.100068 180)
			(size 0.906272 0.906272)
			(drill 0.499872)
			(layers "*.Cu" "*.Mask")
			(remove_unused_layers no)
			(net "GND")
			(clearance 0.0508)
			(thermal_gap 0.0508)
		)
		(pad "D8" thru_hole circle
			(at 15.40002 4.100068 180)
			(size 0.906272 0.906272)
			(drill 0.499872)
			(layers "*.Cu" "*.Mask")
			(remove_unused_layers no)
			(net "GND")
			(clearance 0.0508)
			(thermal_gap 0.0508)
		)
		(pad "D9" thru_hole circle
			(at 17.599914 3.899916 180)
			(size 0.71628 0.71628)
			(drill 0.30988)
			(layers "*.Cu" "*.Mask")
			(remove_unused_layers no)
			(net "SMB_MB_BMC_SCL")
			(clearance 0.0508)
			(thermal_gap 0.0508)
		)
		(pad "D10" thru_hole circle
			(at 19.800062 4.100068 180)
			(size 0.906272 0.906272)
			(drill 0.499872)
			(layers "*.Cu" "*.Mask")
			(remove_unused_layers no)
			(net "GND")
			(clearance 0.0508)
			(thermal_gap 0.0508)
		)
		(pad "E1" thru_hole circle
			(at 0 5.199888 180)
			(size 0.906272 0.906272)
			(drill 0.499872)
			(layers "*.Cu" "*.Mask")
			(remove_unused_layers no)
			(net "GND")
			(clearance 0.0508)
			(thermal_gap 0.0508)
		)
		(pad "E3" thru_hole circle
			(at 4.400042 5.199888 180)
			(size 0.906272 0.906272)
			(drill 0.499872)
			(layers "*.Cu" "*.Mask")
			(remove_unused_layers no)
			(net "GND")
			(clearance 0.0508)
			(thermal_gap 0.0508)
		)
		(pad "E5" thru_hole circle
			(at 8.800084 5.199888 180)
			(size 0.906272 0.906272)
			(drill 0.499872)
			(layers "*.Cu" "*.Mask")
			(remove_unused_layers no)
			(net "GND")
			(clearance 0.0508)
			(thermal_gap 0.0508)
		)
		(pad "E7" thru_hole circle
			(at 13.199872 5.199888 180)
			(size 0.906272 0.906272)
			(drill 0.499872)
			(layers "*.Cu" "*.Mask")
			(remove_unused_layers no)
			(net "GND")
			(clearance 0.0508)
			(thermal_gap 0.0508)
		)
		(pad "E9" thru_hole circle
			(at 17.599914 5.199888 180)
			(size 0.906272 0.906272)
			(drill 0.499872)
			(layers "*.Cu" "*.Mask")
			(remove_unused_layers no)
			(net "GND")
			(clearance 0.0508)
			(thermal_gap 0.0508)
		)
		(pad "E10" thru_hole circle
			(at 19.800062 5.40004 180)
			(size 0.71628 0.71628)
			(drill 0.30988)
			(layers "*.Cu" "*.Mask")
			(remove_unused_layers no)
			(net "Net_4585")
			(clearance 0.0508)
			(thermal_gap 0.0508)
		)
		(pad "F9" thru_hole circle
			(at 17.599914 6.500114 180)
			(size 0.71628 0.71628)
			(drill 0.30988)
			(layers "*.Cu" "*.Mask")
			(remove_unused_layers no)
			(net "SMB_GPU1_ALERT_R_N")
			(clearance 0.0508)
			(thermal_gap 0.0508)
		)
		(pad "F10" thru_hole circle
			(at 19.800062 6.700012 180)
			(size 0.71628 0.71628)
			(drill 0.30988)
			(layers "*.Cu" "*.Mask")
			(remove_unused_layers no)
			(net "Net_4586")
			(clearance 0.0508)
			(thermal_gap 0.0508)
		)
		(pad "G2" thru_hole circle
			(at 2.199894 7.999984 180)
			(size 0.906272 0.906272)
			(drill 0.499872)
			(layers "*.Cu" "*.Mask")
			(remove_unused_layers no)
			(net "GND")
			(clearance 0.0508)
			(thermal_gap 0.0508)
		)
		(pad "G4" thru_hole circle
			(at 6.599936 7.999984 180)
			(size 0.906272 0.906272)
			(drill 0.499872)
			(layers "*.Cu" "*.Mask")
			(remove_unused_layers no)
			(net "GND")
			(clearance 0.0508)
			(thermal_gap 0.0508)
		)
		(pad "G6" thru_hole circle
			(at 10.999978 7.999984 180)
			(size 0.906272 0.906272)
			(drill 0.499872)
			(layers "*.Cu" "*.Mask")
			(remove_unused_layers no)
			(net "GND")
			(clearance 0.0508)
			(thermal_gap 0.0508)
		)
		(pad "G8" thru_hole circle
			(at 15.40002 7.999984 180)
			(size 0.906272 0.906272)
			(drill 0.499872)
			(layers "*.Cu" "*.Mask")
			(remove_unused_layers no)
			(net "GND")
			(clearance 0.0508)
			(thermal_gap 0.0508)
		)
		(pad "G9" thru_hole circle
			(at 17.599914 7.800086 180)
			(size 0.71628 0.71628)
			(drill 0.30988)
			(layers "*.Cu" "*.Mask")
			(remove_unused_layers no)
			(net "MB_BIC_MON_BUF_R")
			(clearance 0.0508)
			(thermal_gap 0.0508)
		)
		(pad "G10" thru_hole circle
			(at 19.800062 7.999984 180)
			(size 0.906272 0.906272)
			(drill 0.499872)
			(layers "*.Cu" "*.Mask")
			(remove_unused_layers no)
			(net "GND")
			(clearance 0.0508)
			(thermal_gap 0.0508)
		)
		(pad "H1" thru_hole circle
			(at 0 9.100058 180)
			(size 0.906272 0.906272)
			(drill 0.499872)
			(layers "*.Cu" "*.Mask")
			(remove_unused_layers no)
			(net "GND")
			(clearance 0.0508)
			(thermal_gap 0.0508)
		)
		(pad "H3" thru_hole circle
			(at 4.400042 9.100058 180)
			(size 0.906272 0.906272)
			(drill 0.499872)
			(layers "*.Cu" "*.Mask")
			(remove_unused_layers no)
			(net "GND")
			(clearance 0.0508)
			(thermal_gap 0.0508)
		)
		(pad "H5" thru_hole circle
			(at 8.800084 9.100058 180)
			(size 0.906272 0.906272)
			(drill 0.499872)
			(layers "*.Cu" "*.Mask")
			(remove_unused_layers no)
			(net "GND")
			(clearance 0.0508)
			(thermal_gap 0.0508)
		)
		(pad "H7" thru_hole circle
			(at 13.199872 9.100058 180)
			(size 0.906272 0.906272)
			(drill 0.499872)
			(layers "*.Cu" "*.Mask")
			(remove_unused_layers no)
			(net "GND")
			(clearance 0.0508)
			(thermal_gap 0.0508)
		)
		(pad "H9" thru_hole circle
			(at 17.599914 9.100058 180)
			(size 0.906272 0.906272)
			(drill 0.499872)
			(layers "*.Cu" "*.Mask")
			(remove_unused_layers no)
			(net "GND")
			(clearance 0.0508)
			(thermal_gap 0.0508)
		)
		(pad "H10" thru_hole circle
			(at 19.800062 9.299956 180)
			(size 0.71628 0.71628)
			(drill 0.30988)
			(layers "*.Cu" "*.Mask")
			(remove_unused_layers no)
			(net "GPU_FPGA_BOOT_EN")
			(clearance 0.0508)
			(thermal_gap 0.0508)
		)
		(pad "I9" thru_hole circle
			(at 17.599914 10.40003 180)
			(size 0.71628 0.71628)
			(drill 0.30988)
			(layers "*.Cu" "*.Mask")
			(remove_unused_layers no)
			(net "Net_4587")
			(clearance 0.0508)
			(thermal_gap 0.0508)
		)
		(pad "I10" thru_hole circle
			(at 19.800062 10.599928 180)
			(size 0.71628 0.71628)
			(drill 0.30988)
			(layers "*.Cu" "*.Mask")
			(remove_unused_layers no)
			(net "MB_BMC_MON")
			(clearance 0.0508)
			(thermal_gap 0.0508)
		)
		(pad "J2" thru_hole circle
			(at 2.199894 11.8999 180)
			(size 0.906272 0.906272)
			(drill 0.499872)
			(layers "*.Cu" "*.Mask")
			(remove_unused_layers no)
			(net "GND")
			(clearance 0.0508)
			(thermal_gap 0.0508)
		)
		(pad "J4" thru_hole circle
			(at 6.599936 11.8999 180)
			(size 0.906272 0.906272)
			(drill 0.499872)
			(layers "*.Cu" "*.Mask")
			(remove_unused_layers no)
			(net "GND")
			(clearance 0.0508)
			(thermal_gap 0.0508)
		)
		(pad "J6" thru_hole circle
			(at 10.999978 11.8999 180)
			(size 0.906272 0.906272)
			(drill 0.499872)
			(layers "*.Cu" "*.Mask")
			(remove_unused_layers no)
			(net "GND")
			(clearance 0.0508)
			(thermal_gap 0.0508)
		)
		(pad "J8" thru_hole circle
			(at 15.40002 11.8999 180)
			(size 0.906272 0.906272)
			(drill 0.499872)
			(layers "*.Cu" "*.Mask")
			(remove_unused_layers no)
			(net "GND")
			(clearance 0.0508)
			(thermal_gap 0.0508)
		)
		(pad "J9" thru_hole circle
			(at 17.599914 11.700002 180)
			(size 0.71628 0.71628)
			(drill 0.30988)
			(layers "*.Cu" "*.Mask")
			(remove_unused_layers no)
			(net "Net_4588")
			(clearance 0.0508)
			(thermal_gap 0.0508)
		)
		(pad "J10" thru_hole circle
			(at 19.800062 11.8999 180)
			(size 0.906272 0.906272)
			(drill 0.499872)
			(layers "*.Cu" "*.Mask")
			(remove_unused_layers no)
			(net "GND")
			(clearance 0.0508)
			(thermal_gap 0.0508)
		)
		(pad "K1" thru_hole circle
			(at 0 12.999974 180)
			(size 0.906272 0.906272)
			(drill 0.499872)
			(layers "*.Cu" "*.Mask")
			(remove_unused_layers no)
			(net "GND")
			(clearance 0.0508)
			(thermal_gap 0.0508)
		)
		(pad "K3" thru_hole circle
			(at 4.400042 12.999974 180)
			(size 0.906272 0.906272)
			(drill 0.499872)
			(layers "*.Cu" "*.Mask")
			(remove_unused_layers no)
			(net "GND")
			(clearance 0.0508)
			(thermal_gap 0.0508)
		)
		(pad "K5" thru_hole circle
			(at 8.800084 12.999974 180)
			(size 0.906272 0.906272)
			(drill 0.499872)
			(layers "*.Cu" "*.Mask")
			(remove_unused_layers no)
			(net "GND")
			(clearance 0.0508)
			(thermal_gap 0.0508)
		)
		(pad "K7" thru_hole circle
			(at 13.199872 12.999974 180)
			(size 0.906272 0.906272)
			(drill 0.499872)
			(layers "*.Cu" "*.Mask")
			(remove_unused_layers no)
			(net "GND")
			(clearance 0.0508)
			(thermal_gap 0.0508)
		)
		(pad "K9" thru_hole circle
			(at 17.599914 12.999974 180)
			(size 0.906272 0.906272)
			(drill 0.499872)
			(layers "*.Cu" "*.Mask")
			(remove_unused_layers no)
			(net "GND")
			(clearance 0.0508)
			(thermal_gap 0.0508)
		)
		(pad "K10" thru_hole circle
			(at 19.800062 13.199872 180)
			(size 0.71628 0.71628)
			(drill 0.30988)
			(layers "*.Cu" "*.Mask")
			(remove_unused_layers no)
			(net "Net_4589")
			(clearance 0.0508)
			(thermal_gap 0.0508)
		)
		(pad "L9" thru_hole circle
			(at 17.599914 14.299946 180)
			(size 0.71628 0.71628)
			(drill 0.30988)
			(layers "*.Cu" "*.Mask")
			(remove_unused_layers no)
			(net "Net_4591")
			(clearance 0.0508)
			(thermal_gap 0.0508)
		)
		(pad "L10" thru_hole circle
			(at 19.800062 14.500098 180)
			(size 0.71628 0.71628)
			(drill 0.30988)
			(layers "*.Cu" "*.Mask")
			(remove_unused_layers no)
			(net "Net_4590")
			(clearance 0.0508)
			(thermal_gap 0.0508)
		)
		(pad "M1_2" thru_hole circle
			(at 2.199894 15.80007 180)
			(size 0.906272 0.906272)
			(drill 0.499872)
			(layers "*.Cu" "*.Mask")
			(remove_unused_layers no)
			(net "GND")
			(clearance 0.0508)
			(thermal_gap 0.0508)
		)
		(pad "M1_4" thru_hole circle
			(at 6.599936 15.80007 180)
			(size 0.906272 0.906272)
			(drill 0.499872)
			(layers "*.Cu" "*.Mask")
			(remove_unused_layers no)
			(net "GND")
			(clearance 0.0508)
			(thermal_gap 0.0508)
		)
		(pad "M1_6" thru_hole circle
			(at 10.999978 15.80007 180)
			(size 0.906272 0.906272)
			(drill 0.499872)
			(layers "*.Cu" "*.Mask")
			(remove_unused_layers no)
			(net "GND")
			(clearance 0.0508)
			(thermal_gap 0.0508)
		)
		(pad "M1_8" thru_hole circle
			(at 15.40002 15.80007 180)
			(size 0.906272 0.906272)
			(drill 0.499872)
			(layers "*.Cu" "*.Mask")
			(remove_unused_layers no)
			(net "GND")
			(clearance 0.0508)
			(thermal_gap 0.0508)
		)
		(pad "M1_10" thru_hole circle
			(at 19.800062 15.80007 180)
			(size 0.906272 0.906272)
			(drill 0.499872)
			(layers "*.Cu" "*.Mask")
			(remove_unused_layers no)
			(net "GND")
			(clearance 0.0508)
			(thermal_gap 0.0508)
		)
		(pad "M2_2" thru_hole circle
			(at 2.199894 26.2001 180)
			(size 0.906272 0.906272)
			(drill 0.499872)
			(layers "*.Cu" "*.Mask")
			(remove_unused_layers no)
			(net "GND")
			(clearance 0.0508)
			(thermal_gap 0.0508)
		)
		(pad "M2_4" thru_hole circle
			(at 6.599936 26.2001 180)
			(size 0.906272 0.906272)
			(drill 0.499872)
			(layers "*.Cu" "*.Mask")
			(remove_unused_layers no)
			(net "GND")
			(clearance 0.0508)
			(thermal_gap 0.0508)
		)
		(pad "M2_6" thru_hole circle
			(at 10.999978 26.2001 180)
			(size 0.906272 0.906272)
			(drill 0.499872)
			(layers "*.Cu" "*.Mask")
			(remove_unused_layers no)
			(net "GND")
			(clearance 0.0508)
			(thermal_gap 0.0508)
		)
		(pad "M2_8" thru_hole circle
			(at 15.40002 26.2001 180)
			(size 0.906272 0.906272)
			(drill 0.499872)
			(layers "*.Cu" "*.Mask")
			(remove_unused_layers no)
			(net "GND")
			(clearance 0.0508)
			(thermal_gap 0.0508)
		)
		(pad "M2_10" thru_hole circle
			(at 19.800062 26.2001 180)
			(size 0.906272 0.906272)
			(drill 0.499872)
			(layers "*.Cu" "*.Mask")
			(remove_unused_layers no)
			(net "GND")
			(clearance 0.0508)
			(thermal_gap 0.0508)
		)
		(pad "M9" thru_hole circle
			(at 17.599914 15.599918 180)
			(size 0.71628 0.71628)
			(drill 0.30988)
			(layers "*.Cu" "*.Mask")
			(remove_unused_layers no)
			(net "Net_4592")
			(clearance 0.0508)
			(thermal_gap 0.0508)
		)
		(pad "N1_1" thru_hole circle
			(at 0 16.89989 180)
			(size 0.906272 0.906272)
			(drill 0.499872)
			(layers "*.Cu" "*.Mask")
			(remove_unused_layers no)
			(net "GND")
			(clearance 0.0508)
			(thermal_gap 0.0508)
		)
		(pad "N1_3" thru_hole circle
			(at 4.400042 16.89989 180)
			(size 0.906272 0.906272)
			(drill 0.499872)
			(layers "*.Cu" "*.Mask")
			(remove_unused_layers no)
			(net "GND")
			(clearance 0.0508)
			(thermal_gap 0.0508)
		)
		(pad "N1_5" thru_hole circle
			(at 8.800084 16.89989 180)
			(size 0.906272 0.906272)
			(drill 0.499872)
			(layers "*.Cu" "*.Mask")
			(remove_unused_layers no)
			(net "GND")
			(clearance 0.0508)
			(thermal_gap 0.0508)
		)
		(pad "N1_7" thru_hole circle
			(at 13.199872 16.89989 180)
			(size 0.906272 0.906272)
			(drill 0.499872)
			(layers "*.Cu" "*.Mask")
			(remove_unused_layers no)
			(net "GND")
			(clearance 0.0508)
			(thermal_gap 0.0508)
		)
		(pad "N1_9" thru_hole circle
			(at 17.599914 16.89989 180)
			(size 0.906272 0.906272)
			(drill 0.499872)
			(layers "*.Cu" "*.Mask")
			(remove_unused_layers no)
			(net "GND")
			(clearance 0.0508)
			(thermal_gap 0.0508)
		)
		(pad "N2_1" thru_hole circle
			(at 0 27.29992 180)
			(size 0.906272 0.906272)
			(drill 0.499872)
			(layers "*.Cu" "*.Mask")
			(remove_unused_layers no)
			(net "GND")
			(clearance 0.0508)
			(thermal_gap 0.0508)
		)
	)
)
